(kicad_pcb
	(version 20260206)
	(generator "pcbnew")
	(generator_version "10.0")
	(general
		(thickness 1.6)
		(legacy_teardrops no)
	)
	(paper "A4")
	(title_block
		(title "Bryce Canyon_F.DPB_16315-1-OCP.brd")
		(comment 1 "Bryce Canyon / footprints 1534-1538 of 2223")
	)
	(layers
		(0 "F.Cu" signal "TOP")
		(4 "In1.Cu" signal "L2GND")
		(6 "In2.Cu" signal "L3")
		(8 "In3.Cu" signal "L4GND")
		(10 "In4.Cu" signal "L5")
		(12 "In5.Cu" signal "L6VCC")
		(14 "In6.Cu" signal "L7VCC")
		(16 "In7.Cu" signal "L8")
		(18 "In8.Cu" signal "L9GND")
		(20 "In9.Cu" signal "L10")
		(22 "In10.Cu" signal "L11GND")
		(2 "B.Cu" signal "BOTTOM")
		(9 "F.Adhes" user "F.Adhesive")
		(11 "B.Adhes" user "B.Adhesive")
		(13 "F.Paste" user "Package Geometry/Pastemask Top")
		(15 "B.Paste" user "Package Geometry/Pastemask Bottom")
		(5 "F.SilkS" user "Ref Des/Silkscreen Top")
		(7 "B.SilkS" user "Ref Des/Silkscreen Bottom")
		(1 "F.Mask" user "Board Geometry/Soldermask Top")
		(3 "B.Mask" user "Board Geometry/Soldermask Bottom")
		(17 "Dwgs.User" user "User.Drawings")
		(19 "Cmts.User" user "User.Comments")
		(21 "Eco1.User" user "User.Eco1")
		(23 "Eco2.User" user "User.Eco2")
		(25 "Edge.Cuts" user "Board Geometry/Outline")
		(27 "Margin" user)
		(31 "F.CrtYd" user "Package Geometry/Place Bound Top")
		(29 "B.CrtYd" user "Package Geometry/Place Bound Bottom")
		(35 "F.Fab" user "Ref Des/Assembly Top")
		(33 "B.Fab" user "Ref Des/Assembly Bottom")
	)
	(footprint ""
		(layer "F.Cu")
		(at 276.225 -278.384)
		(property "Reference" "U11"
			(at 0 0 0)
			(layer "F.SilkS")
			(hide yes)
			(effects
				(font
					(size 1.27 1.27)
				)
			)
		)
		(property "Value" "TCA9555PWR-GP"
			(at 0 -6.9342 0)
			(unlocked yes)
			(layer "F.Fab")
			(hide yes)
			(effects
				(font
					(size 1.016 1.016)
					(thickness 0.1524)
				)
			)
		)
		(property "Device Type" "TSOIC24H48"
			(at 0 -8.5852 0)
			(unlocked yes)
			(layer "F.Fab")
			(hide yes)
			(effects
				(font
					(size 1.016 1.016)
					(thickness 0.1524)
				)
			)
		)
		(duplicate_pad_numbers_are_jumpers no)
		(fp_line
			(start -4.2291 -1.397)
			(end 3.81 -1.397)
			(stroke
				(width 0.1524)
				(type default)
			)
			(layer "F.SilkS")
		)
		(fp_line
			(start -4.2291 -0.8001)
			(end -3.429 0)
			(stroke
				(width 0.1524)
				(type default)
			)
			(layer "F.SilkS")
		)
		(fp_line
			(start -4.2291 3.937)
			(end -4.2291 -1.397)
			(stroke
				(width 0.1524)
				(type default)
			)
			(layer "F.SilkS")
		)
		(fp_line
			(start -4.22656 3.81)
			(end -4.2291 1.397)
			(stroke
				(width 0.508)
				(type default)
			)
			(layer "F.SilkS")
		)
		(fp_line
			(start -3.429 0)
			(end -4.2291 0.8001)
			(stroke
				(width 0.1524)
				(type default)
			)
			(layer "F.SilkS")
		)
		(fp_line
			(start 3.81 -1.397)
			(end 3.81 1.397)
			(stroke
				(width 0.1524)
				(type default)
			)
			(layer "F.SilkS")
		)
		(fp_line
			(start 3.81 1.397)
			(end -4.2291 1.397)
			(stroke
				(width 0.1524)
				(type default)
			)
			(layer "F.SilkS")
		)
		(fp_poly
			(pts
				(xy -3.90652 -1.8542) (xy 3.90652 -1.8542) (xy 3.90652 1.8542) (xy -3.90652 1.8542)
			)
			(stroke
				(width 0)
				(type default)
			)
			(fill yes)
			(layer "F.SilkS")
		)
		(fp_poly
			(pts
				(xy -4.2164 3.81) (xy 4.2164 3.81) (xy 4.22656 -3.81) (xy -4.2164 -3.81)
			)
			(stroke
				(width 0)
				(type default)
			)
			(fill no)
			(layer "F.CrtYd")
		)
		(fp_poly
			(pts
				(xy -4.22656 -3.81) (xy 4.22656 -3.81) (xy 4.22656 3.81) (xy -4.22656 3.81)
			)
			(stroke
				(width 0)
				(type default)
			)
			(fill no)
			(layer "F.Fab")
		)
		(pad "1" smd rect
			(at -3.57632 2.8194)
			(size 0.3556 1.524)
			(layers "F.Cu" "F.Mask" "F.Paste")
			(net "IO_EXP1_HDD_FAULT_INT_N")
		)
		(pad "2" smd rect
			(at -2.92608 2.8194)
			(size 0.3556 1.524)
			(layers "F.Cu" "F.Mask" "F.Paste")
			(net "IO_EXP1_HDD_FAULT_A1")
		)
		(pad "3" smd rect
			(at -2.27584 2.8194)
			(size 0.3556 1.524)
			(layers "F.Cu" "F.Mask" "F.Paste")
			(net "IO_EXP1_HDD_FAULT_A2")
		)
		(pad "4" smd rect
			(at -1.6256 2.8194)
			(size 0.3556 1.524)
			(layers "F.Cu" "F.Mask" "F.Paste")
			(net "DRIVE_A_16_FLT_LED")
		)
		(pad "5" smd rect
			(at -0.97536 2.8194)
			(size 0.3556 1.524)
			(layers "F.Cu" "F.Mask" "F.Paste")
			(net "DRIVE_A_17_FLT_LED")
		)
		(pad "6" smd rect
			(at -0.32512 2.8194)
			(size 0.3556 1.524)
			(layers "F.Cu" "F.Mask" "F.Paste")
			(net "DRIVE_A_18_FLT_LED")
		)
		(pad "7" smd rect
			(at 0.32512 2.8194)
			(size 0.3556 1.524)
			(layers "F.Cu" "F.Mask" "F.Paste")
			(net "DRIVE_A_19_FLT_LED")
		)
		(pad "8" smd rect
			(at 0.97536 2.8194)
			(size 0.3556 1.524)
			(layers "F.Cu" "F.Mask" "F.Paste")
			(net "DRIVE_A_20_FLT_LED")
		)
		(pad "9" smd rect
			(at 1.6256 2.8194)
			(size 0.3556 1.524)
			(layers "F.Cu" "F.Mask" "F.Paste")
			(net "DRIVE_A_21_FLT_LED")
		)
		(pad "10" smd rect
			(at 2.27584 2.8194)
			(size 0.3556 1.524)
			(layers "F.Cu" "F.Mask" "F.Paste")
			(net "DRIVE_A_22_FLT_LED")
		)
		(pad "11" smd rect
			(at 2.92608 2.8194)
			(size 0.3556 1.524)
			(layers "F.Cu" "F.Mask" "F.Paste")
			(net "DRIVE_A_23_FLT_LED")
		)
		(pad "12" smd rect
			(at 3.57632 2.8194)
			(size 0.3556 1.524)
			(layers "F.Cu" "F.Mask" "F.Paste")
			(net "GND")
		)
		(pad "13" smd rect
			(at 3.57632 -2.8194)
			(size 0.3556 1.524)
			(layers "F.Cu" "F.Mask" "F.Paste")
			(net "FRONT_FAN_LED0")
		)
		(pad "14" smd rect
			(at 2.92608 -2.8194)
			(size 0.3556 1.524)
			(layers "F.Cu" "F.Mask" "F.Paste")
			(net "FRONT_FAN_LED1")
		)
		(pad "15" smd rect
			(at 2.27584 -2.8194)
			(size 0.3556 1.524)
			(layers "F.Cu" "F.Mask" "F.Paste")
			(net "FRONT_FAN_LED2")
		)
		(pad "16" smd rect
			(at 1.6256 -2.8194)
			(size 0.3556 1.524)
			(layers "F.Cu" "F.Mask" "F.Paste")
			(net "FRONT_FAN_LED3")
		)
		(pad "17" smd rect
			(at 0.97536 -2.8194)
			(size 0.3556 1.524)
			(layers "F.Cu" "F.Mask" "F.Paste")
			(net "Net_241")
		)
		(pad "18" smd rect
			(at 0.32512 -2.8194)
			(size 0.3556 1.524)
			(layers "F.Cu" "F.Mask" "F.Paste")
			(net "Net_242")
		)
		(pad "19" smd rect
			(at -0.32512 -2.8194)
			(size 0.3556 1.524)
			(layers "F.Cu" "F.Mask" "F.Paste")
			(net "Net_243")
		)
		(pad "20" smd rect
			(at -0.97536 -2.8194)
			(size 0.3556 1.524)
			(layers "F.Cu" "F.Mask" "F.Paste")
			(net "Net_244")
		)
		(pad "21" smd rect
			(at -1.6256 -2.8194)
			(size 0.3556 1.524)
			(layers "F.Cu" "F.Mask" "F.Paste")
			(net "IO_EXP1_HDD_FAULT_A0")
		)
		(pad "22" smd rect
			(at -2.27584 -2.8194)
			(size 0.3556 1.524)
			(layers "F.Cu" "F.Mask" "F.Paste")
			(net "IO_EXP1_LED_SCL")
		)
		(pad "23" smd rect
			(at -2.92608 -2.8194)
			(size 0.3556 1.524)
			(layers "F.Cu" "F.Mask" "F.Paste")
			(net "IO_EXP1_LED_SDA")
		)
		(pad "24" smd rect
			(at -3.57632 -2.8194)
			(size 0.3556 1.524)
			(layers "F.Cu" "F.Mask" "F.Paste")
			(net "P3V3_STBY_A")
		)
	)
	(footprint ""
		(layer "F.Cu")
		(at 83.530948 -62.778894 -90)
		(property "Reference" "C378"
			(at 0 0 270)
			(layer "F.SilkS")
			(hide yes)
			(effects
				(font
					(size 1.27 1.27)
				)
			)
		)
		(property "Value" "SC1U16V3KX-5GP"
			(at 0 -2.8194 270)
			(unlocked yes)
			(layer "F.Fab")
			(hide yes)
			(effects
				(font
					(size 1.016 1.016)
					(thickness 0.1524)
				)
			)
		)
		(property "Device Type" "C603H36"
			(at 0 -4.3434 270)
			(unlocked yes)
			(layer "F.Fab")
			(hide yes)
			(effects
				(font
					(size 1.016 1.016)
					(thickness 0.1524)
				)
			)
		)
		(duplicate_pad_numbers_are_jumpers no)
		(fp_line
			(start 0.508 0)
			(end -0.508 0)
			(stroke
				(width 0.2032)
				(type default)
			)
			(layer "F.SilkS")
		)
		(fp_rect
			(start -0.5842 1.3335)
			(end 0.5842 -1.3335)
			(stroke
				(width 0)
				(type default)
			)
			(fill no)
			(layer "F.CrtYd")
		)
		(fp_rect
			(start -0.5842 1.3335)
			(end 0.5842 -1.3335)
			(stroke
				(width 0)
				(type default)
			)
			(fill no)
			(layer "F.Fab")
		)
		(pad "1" smd custom
			(at 0 -0.762 270)
			(size 0.2159 0.2159)
			(layers "F.Cu" "F.Mask" "F.Paste")
			(net "P5V_HDD26")
			(options
				(clearance outline)
				(anchor circle)
			)
			(primitives
				(gr_poly
					(pts
						(arc
							(start -0.3302 -0.4318)
							(mid -0.402042 -0.402042)
							(end -0.4318 -0.3302)
						)
						(arc
							(start -0.4318 0.3302)
							(mid -0.402042 0.402042)
							(end -0.3302 0.4318)
						)
						(arc
							(start 0.3302 0.4318)
							(mid 0.402042 0.402042)
							(end 0.4318 0.3302)
						)
						(arc
							(start 0.4318 -0.3302)
							(mid 0.402042 -0.402042)
							(end 0.3302 -0.4318)
						)
					)
					(width 0)
					(fill yes)
				)
			)
		)
		(pad "2" smd custom
			(at 0 0.762 270)
			(size 0.2159 0.2159)
			(layers "F.Cu" "F.Mask" "F.Paste")
			(net "GND")
			(options
				(clearance outline)
				(anchor circle)
			)
			(primitives
				(gr_poly
					(pts
						(arc
							(start -0.3302 -0.4318)
							(mid -0.402042 -0.402042)
							(end -0.4318 -0.3302)
						)
						(arc
							(start -0.4318 0.3302)
							(mid -0.402042 0.402042)
							(end -0.3302 0.4318)
						)
						(arc
							(start 0.3302 0.4318)
							(mid 0.402042 0.402042)
							(end 0.4318 0.3302)
						)
						(arc
							(start 0.4318 -0.3302)
							(mid 0.402042 -0.402042)
							(end 0.3302 -0.4318)
						)
					)
					(width 0)
					(fill yes)
				)
			)
		)
	)
	(footprint ""
		(layer "F.Cu")
		(at 181.991 -189.462918 180)
		(property "Reference" "C268"
			(at 0 0 180)
			(layer "F.SilkS")
			(hide yes)
			(effects
				(font
					(size 1.27 1.27)
				)
			)
		)
		(property "Value" "SC1U25V3KX-GP"
			(at 0 -2.8194 180)
			(unlocked yes)
			(layer "F.Fab")
			(hide yes)
			(effects
				(font
					(size 1.016 1.016)
					(thickness 0.1524)
				)
			)
		)
		(property "Device Type" "C603H36"
			(at 0 -4.3434 180)
			(unlocked yes)
			(layer "F.Fab")
			(hide yes)
			(effects
				(font
					(size 1.016 1.016)
					(thickness 0.1524)
				)
			)
		)
		(duplicate_pad_numbers_are_jumpers no)
		(fp_line
			(start 0.508 0)
			(end -0.508 0)
			(stroke
				(width 0.2032)
				(type default)
			)
			(layer "F.SilkS")
		)
		(fp_rect
			(start -0.5842 1.3335)
			(end 0.5842 -1.3335)
			(stroke
				(width 0)
				(type default)
			)
			(fill no)
			(layer "F.CrtYd")
		)
		(fp_rect
			(start -0.5842 1.3335)
			(end 0.5842 -1.3335)
			(stroke
				(width 0)
				(type default)
			)
			(fill no)
			(layer "F.Fab")
		)
		(pad "1" smd custom
			(at 0 -0.762 180)
			(size 0.2159 0.2159)
			(layers "F.Cu" "F.Mask" "F.Paste")
			(net "P12V_HDD17")
			(options
				(clearance outline)
				(anchor circle)
			)
			(primitives
				(gr_poly
					(pts
						(arc
							(start -0.3302 -0.4318)
							(mid -0.402042 -0.402042)
							(end -0.4318 -0.3302)
						)
						(arc
							(start -0.4318 0.3302)
							(mid -0.402042 0.402042)
							(end -0.3302 0.4318)
						)
						(arc
							(start 0.3302 0.4318)
							(mid 0.402042 0.402042)
							(end 0.4318 0.3302)
						)
						(arc
							(start 0.4318 -0.3302)
							(mid 0.402042 -0.402042)
							(end 0.3302 -0.4318)
						)
					)
					(width 0)
					(fill yes)
				)
			)
		)
		(pad "2" smd custom
			(at 0 0.762 180)
			(size 0.2159 0.2159)
			(layers "F.Cu" "F.Mask" "F.Paste")
			(net "GND")
			(options
				(clearance outline)
				(anchor circle)
			)
			(primitives
				(gr_poly
					(pts
						(arc
							(start -0.3302 -0.4318)
							(mid -0.402042 -0.402042)
							(end -0.4318 -0.3302)
						)
						(arc
							(start -0.4318 0.3302)
							(mid -0.402042 0.402042)
							(end -0.3302 0.4318)
						)
						(arc
							(start 0.3302 0.4318)
							(mid 0.402042 0.402042)
							(end 0.4318 0.3302)
						)
						(arc
							(start 0.4318 -0.3302)
							(mid 0.402042 -0.402042)
							(end 0.3302 -0.4318)
						)
					)
					(width 0)
					(fill yes)
				)
			)
		)
	)
	(footprint ""
		(layer "F.Cu")
		(at 83.149948 -176.000918 -90)
		(property "Reference" "C223"
			(at 0 0 270)
			(layer "F.SilkS")
			(hide yes)
			(effects
				(font
					(size 1.27 1.27)
				)
			)
		)
		(property "Value" "SC10U16V6KX-2GP"
			(at -0.0762 -5.1308 270)
			(unlocked yes)
			(layer "F.Fab")
			(hide yes)
			(effects
				(font
					(size 1.016 1.016)
					(thickness 0.1524)
				)
			)
		)
		(property "Device Type" "C1206H71"
			(at -0.127 -6.6548 270)
			(unlocked yes)
			(layer "F.Fab")
			(hide yes)
			(effects
				(font
					(size 1.016 1.016)
					(thickness 0.1524)
				)
			)
		)
		(duplicate_pad_numbers_are_jumpers no)
		(fp_line
			(start -1.016 2.2352)
			(end -1.016 0.8382)
			(stroke
				(width 0.1524)
				(type default)
			)
			(layer "F.SilkS")
		)
		(fp_line
			(start 1.016 2.2352)
			(end -1.016 2.2352)
			(stroke
				(width 0.1524)
				(type default)
			)
			(layer "F.SilkS")
		)
		(fp_line
			(start 1.016 0.8382)
			(end 1.016 2.2352)
			(stroke
				(width 0.1524)
				(type default)
			)
			(layer "F.SilkS")
		)
		(fp_line
			(start -1.016 -0.8382)
			(end -1.016 -2.2352)
			(stroke
				(width 0.1524)
				(type default)
			)
			(layer "F.SilkS")
		)
		(fp_line
			(start -1.016 -2.2352)
			(end 1.016 -2.2352)
			(stroke
				(width 0.1524)
				(type default)
			)
			(layer "F.SilkS")
		)
		(fp_line
			(start 1.016 -2.2352)
			(end 1.016 -0.8382)
			(stroke
				(width 0.1524)
				(type default)
			)
			(layer "F.SilkS")
		)
		(fp_rect
			(start -1.0922 2.3114)
			(end 1.0922 -2.3114)
			(stroke
				(width 0)
				(type default)
			)
			(fill no)
			(layer "F.CrtYd")
		)
		(fp_poly
			(pts
				(xy 1.0922 -2.3114) (xy 1.0922 2.3114) (xy -1.0922 2.3114) (xy -1.0922 -2.3114)
			)
			(stroke
				(width 0)
				(type default)
			)
			(fill no)
			(layer "F.Fab")
		)
		(pad "1" smd rect
			(at 0 -1.397 270)
			(size 1.651 1.27)
			(layers "F.Cu" "F.Mask" "F.Paste")
			(net "P5V_HDD14")
		)
		(pad "2" smd rect
			(at 0 1.397 270)
			(size 1.651 1.27)
			(layers "F.Cu" "F.Mask" "F.Paste")
			(net "GND")
		)
	)
	(footprint ""
		(layer "F.Cu")
		(at 218.059 -384.81 180)
		(property "Reference" "Q21"
			(at 0 0 180)
			(layer "F.SilkS")
			(hide yes)
			(effects
				(font
					(size 1.27 1.27)
				)
			)
		)
		(property "Value" "2N7002K-1-GP"
			(at 0.127 -8.9662 180)
			(unlocked yes)
			(layer "F.Fab")
			(hide yes)
			(effects
				(font
					(size 1.016 1.016)
					(thickness 0.1524)
				)
			)
		)
		(property "Device Type" "SOT23DGS2D4H44"
			(at 0.127 -10.4902 180)
			(unlocked yes)
			(layer "F.Fab")
			(hide yes)
			(effects
				(font
					(size 1.016 1.016)
					(thickness 0.1524)
				)
			)
		)
		(duplicate_pad_numbers_are_jumpers no)
		(fp_line
			(start 1.651 1.778)
			(end 1.651 -1.778)
			(stroke
				(width 0.1524)
				(type default)
			)
			(layer "F.SilkS")
		)
		(fp_line
			(start 1.651 -1.778)
			(end -1.651 -1.778)
			(stroke
				(width 0.1524)
				(type default)
			)
			(layer "F.SilkS")
		)
		(fp_line
			(start -1.651 1.778)
			(end 1.651 1.778)
			(stroke
				(width 0.1524)
				(type default)
			)
			(layer "F.SilkS")
		)
		(fp_line
			(start -1.651 -1.778)
			(end -1.651 1.778)
			(stroke
				(width 0.1524)
				(type default)
			)
			(layer "F.SilkS")
		)
		(fp_poly
			(pts
				(xy -1.778 1.8796) (xy -1.778 -1.8796) (xy 1.778 -1.8796) (xy 1.778 1.8796)
			)
			(stroke
				(width 0)
				(type default)
			)
			(fill no)
			(layer "F.CrtYd")
		)
		(fp_poly
			(pts
				(xy -1.778 1.8796) (xy -1.778 -1.8796) (xy 1.778 -1.8796) (xy 1.778 1.8796)
			)
			(stroke
				(width 0)
				(type default)
			)
			(fill no)
			(layer "F.Fab")
		)
		(pad "D" smd custom
			(at 0 -0.9525 180)
			(size 0.1905 0.1905)
			(layers "F.Cu" "F.Mask" "F.Paste")
			(net "SCC_FULL_PWR_EN_5V_R")
			(options
				(clearance outline)
				(anchor circle)
			)
			(primitives
				(gr_poly
					(pts
						(arc
							(start -0.1778 0.5715)
							(mid -0.321484 0.511984)
							(end -0.381 0.3683)
						)
						(arc
							(start -0.381 -0.3683)
							(mid -0.321484 -0.511984)
							(end -0.1778 -0.5715)
						)
						(arc
							(start 0.1778 -0.5715)
							(mid 0.321484 -0.511984)
							(end 0.381 -0.3683)
						)
						(arc
							(start 0.381 0.3683)
							(mid 0.321484 0.511984)
							(end 0.1778 0.5715)
						)
					)
					(width 0)
					(fill yes)
				)
			)
		)
		(pad "G" smd custom
			(at -0.98425 0.9525 180)
			(size 0.1905 0.1905)
			(layers "F.Cu" "F.Mask" "F.Paste")
			(net "SCC_A_FULL_PWR_EN_12V")
			(options
				(clearance outline)
				(anchor circle)
			)
			(primitives
				(gr_poly
					(pts
						(arc
							(start -0.1778 0.5715)
							(mid -0.321484 0.511984)
							(end -0.381 0.3683)
						)
						(arc
							(start -0.381 -0.3683)
							(mid -0.321484 -0.511984)
							(end -0.1778 -0.5715)
						)
						(arc
							(start 0.1778 -0.5715)
							(mid 0.321484 -0.511984)
							(end 0.381 -0.3683)
						)
						(arc
							(start 0.381 0.3683)
							(mid 0.321484 0.511984)
							(end 0.1778 0.5715)
						)
					)
					(width 0)
					(fill yes)
				)
			)
		)
		(pad "S" smd custom
			(at 0.98425 0.9525 180)
			(size 0.1905 0.1905)
			(layers "F.Cu" "F.Mask" "F.Paste")
			(net "GND")
			(options
				(clearance outline)
				(anchor circle)
			)
			(primitives
				(gr_poly
					(pts
						(arc
							(start -0.1778 0.5715)
							(mid -0.321484 0.511984)
							(end -0.381 0.3683)
						)
						(arc
							(start -0.381 -0.3683)
							(mid -0.321484 -0.511984)
							(end -0.1778 -0.5715)
						)
						(arc
							(start 0.1778 -0.5715)
							(mid 0.321484 -0.511984)
							(end 0.381 -0.3683)
						)
						(arc
							(start 0.381 0.3683)
							(mid 0.321484 0.511984)
							(end 0.1778 0.5715)
						)
					)
					(width 0)
					(fill yes)
				)
			)
		)
	)
)
